(kicad_sch
	(version 20250114)
	(generator "eeschema")
	(generator_version "9.0")
	(paper "A3")
	(title_block
		(title "OCuLink to PCIe adapter")
		(date "2025-06-18")
		(rev "1.0.0")
		(company "Antmicro Ltd")
		(comment 1 "www.antmicro.com")
	)
	(text "Power input connectors"
		(exclude_from_sim no)
		(at 128.27 177.165 0)
		(effects
			(font
				(size 1.27 1.27)
			)
		)
	)
	(text "EPS-12V power connector\n(CPU 4+4)"
		(exclude_from_sim no)
		(at 88.138 217.17 0)
		(effects
			(font
				(size 1.27 1.27)
			)
			(justify left)
		)
	)
	(text "Nano-fit power connector"
		(exclude_from_sim no)
		(at 110.49 192.405 0)
		(effects
			(font
				(size 1.27 1.27)
			)
			(justify right)
		)
	)
	(junction
		(at 271.78 182.88)
		(diameter 0)
		(color 0 0 0 0)
	)
	(junction
		(at 271.78 190.5)
		(diameter 0)
		(color 0 0 0 0)
	)
	(junction
		(at 116.84 217.17)
		(diameter 0)
		(color 0 0 0 0)
	)
	(junction
		(at 147.32 212.09)
		(diameter 0)
		(color 0 0 0 0)
	)
	(junction
		(at 116.84 219.71)
		(diameter 0)
		(color 0 0 0 0)
	)
	(junction
		(at 137.16 187.96)
		(diameter 0)
		(color 0 0 0 0)
	)
	(junction
		(at 147.32 187.96)
		(diameter 0)
		(color 0 0 0 0)
	)
	(junction
		(at 116.84 214.63)
		(diameter 0)
		(color 0 0 0 0)
	)
	(junction
		(at 271.78 198.12)
		(diameter 0)
		(color 0 0 0 0)
	)
	(junction
		(at 124.46 193.04)
		(diameter 0)
		(color 0 0 0 0)
	)
	(junction
		(at 134.62 214.63)
		(diameter 0)
		(color 0 0 0 0)
	)
	(junction
		(at 134.62 217.17)
		(diameter 0)
		(color 0 0 0 0)
	)
	(junction
		(at 271.78 175.26)
		(diameter 0)
		(color 0 0 0 0)
	)
	(junction
		(at 254 120.65)
		(diameter 0)
		(color 0 0 0 0)
	)
	(junction
		(at 134.62 212.09)
		(diameter 0)
		(color 0 0 0 0)
	)
	(junction
		(at 137.16 212.09)
		(diameter 0)
		(color 0 0 0 0)
	)
	(wire
		(pts
			(xy 116.84 212.09) (xy 119.38 212.09)
		)
		(stroke
			(width 0)
			(type default)
		)
	)
	(wire
		(pts
			(xy 132.08 214.63) (xy 134.62 214.63)
		)
		(stroke
			(width 0)
			(type default)
		)
	)
	(wire
		(pts
			(xy 116.84 219.71) (xy 119.38 219.71)
		)
		(stroke
			(width 0)
			(type default)
		)
	)
	(wire
		(pts
			(xy 132.08 212.09) (xy 134.62 212.09)
		)
		(stroke
			(width 0)
			(type default)
		)
	)
	(wire
		(pts
			(xy 271.78 175.26) (xy 274.32 175.26)
		)
		(stroke
			(width 0)
			(type default)
		)
	)
	(wire
		(pts
			(xy 186.69 133.35) (xy 137.16 133.35)
		)
		(stroke
			(width 0)
			(type default)
		)
	)
	(wire
		(pts
			(xy 147.32 187.96) (xy 153.67 187.96)
		)
		(stroke
			(width 0)
			(type default)
		)
	)
	(wire
		(pts
			(xy 147.32 187.96) (xy 147.32 196.85)
		)
		(stroke
			(width 0)
			(type default)
		)
	)
	(bus
		(pts
			(xy 254 120.65) (xy 273.05 120.65)
		)
		(stroke
			(width 0)
			(type default)
		)
	)
	(wire
		(pts
			(xy 137.16 130.81) (xy 189.23 130.81)
		)
		(stroke
			(width 0)
			(type default)
		)
	)
	(wire
		(pts
			(xy 137.16 210.82) (xy 137.16 212.09)
		)
		(stroke
			(width 0)
			(type default)
		)
	)
	(wire
		(pts
			(xy 271.78 198.12) (xy 271.78 199.39)
		)
		(stroke
			(width 0)
			(type default)
		)
	)
	(wire
		(pts
			(xy 134.62 214.63) (xy 134.62 217.17)
		)
		(stroke
			(width 0)
			(type default)
		)
	)
	(wire
		(pts
			(xy 179.07 162.56) (xy 191.77 162.56)
		)
		(stroke
			(width 0)
			(type default)
		)
	)
	(wire
		(pts
			(xy 271.78 198.12) (xy 274.32 198.12)
		)
		(stroke
			(width 0)
			(type default)
		)
	)
	(wire
		(pts
			(xy 123.19 193.04) (xy 124.46 193.04)
		)
		(stroke
			(width 0)
			(type default)
		)
	)
	(wire
		(pts
			(xy 134.62 217.17) (xy 134.62 219.71)
		)
		(stroke
			(width 0)
			(type default)
		)
	)
	(wire
		(pts
			(xy 124.46 193.04) (xy 124.46 194.31)
		)
		(stroke
			(width 0)
			(type default)
		)
	)
	(wire
		(pts
			(xy 274.32 190.5) (xy 271.78 190.5)
		)
		(stroke
			(width 0)
			(type default)
		)
	)
	(wire
		(pts
			(xy 271.78 167.64) (xy 271.78 175.26)
		)
		(stroke
			(width 0)
			(type default)
		)
	)
	(wire
		(pts
			(xy 137.16 186.69) (xy 137.16 187.96)
		)
		(stroke
			(width 0)
			(type default)
		)
	)
	(wire
		(pts
			(xy 116.84 214.63) (xy 116.84 217.17)
		)
		(stroke
			(width 0)
			(type default)
		)
	)
	(wire
		(pts
			(xy 116.84 214.63) (xy 119.38 214.63)
		)
		(stroke
			(width 0)
			(type default)
		)
	)
	(wire
		(pts
			(xy 116.84 217.17) (xy 116.84 219.71)
		)
		(stroke
			(width 0)
			(type default)
		)
	)
	(wire
		(pts
			(xy 134.62 212.09) (xy 137.16 212.09)
		)
		(stroke
			(width 0)
			(type default)
		)
	)
	(wire
		(pts
			(xy 191.77 162.56) (xy 191.77 130.81)
		)
		(stroke
			(width 0)
			(type default)
		)
	)
	(wire
		(pts
			(xy 137.16 128.27) (xy 273.05 128.27)
		)
		(stroke
			(width 0)
			(type default)
		)
	)
	(bus
		(pts
			(xy 254 158.75) (xy 254 120.65)
		)
		(stroke
			(width 0)
			(type default)
		)
	)
	(wire
		(pts
			(xy 274.32 167.64) (xy 271.78 167.64)
		)
		(stroke
			(width 0)
			(type default)
		)
	)
	(wire
		(pts
			(xy 271.78 175.26) (xy 271.78 182.88)
		)
		(stroke
			(width 0)
			(type default)
		)
	)
	(wire
		(pts
			(xy 137.16 161.29) (xy 153.67 161.29)
		)
		(stroke
			(width 0)
			(type default)
		)
	)
	(wire
		(pts
			(xy 189.23 160.02) (xy 179.07 160.02)
		)
		(stroke
			(width 0)
			(type default)
		)
	)
	(wire
		(pts
			(xy 123.19 187.96) (xy 137.16 187.96)
		)
		(stroke
			(width 0)
			(type default)
		)
	)
	(wire
		(pts
			(xy 134.62 212.09) (xy 134.62 214.63)
		)
		(stroke
			(width 0)
			(type default)
		)
	)
	(wire
		(pts
			(xy 191.77 130.81) (xy 273.05 130.81)
		)
		(stroke
			(width 0)
			(type default)
		)
	)
	(wire
		(pts
			(xy 147.32 201.93) (xy 147.32 212.09)
		)
		(stroke
			(width 0)
			(type default)
		)
	)
	(wire
		(pts
			(xy 137.16 187.96) (xy 147.32 187.96)
		)
		(stroke
			(width 0)
			(type default)
		)
	)
	(wire
		(pts
			(xy 271.78 182.88) (xy 274.32 182.88)
		)
		(stroke
			(width 0)
			(type default)
		)
	)
	(wire
		(pts
			(xy 116.84 212.09) (xy 116.84 214.63)
		)
		(stroke
			(width 0)
			(type default)
		)
	)
	(wire
		(pts
			(xy 189.23 130.81) (xy 189.23 160.02)
		)
		(stroke
			(width 0)
			(type default)
		)
	)
	(wire
		(pts
			(xy 147.32 212.09) (xy 153.67 212.09)
		)
		(stroke
			(width 0)
			(type default)
		)
	)
	(wire
		(pts
			(xy 271.78 182.88) (xy 271.78 190.5)
		)
		(stroke
			(width 0)
			(type default)
		)
	)
	(wire
		(pts
			(xy 116.84 217.17) (xy 119.38 217.17)
		)
		(stroke
			(width 0)
			(type default)
		)
	)
	(wire
		(pts
			(xy 137.16 212.09) (xy 147.32 212.09)
		)
		(stroke
			(width 0)
			(type default)
		)
	)
	(wire
		(pts
			(xy 132.08 219.71) (xy 134.62 219.71)
		)
		(stroke
			(width 0)
			(type default)
		)
	)
	(bus
		(pts
			(xy 137.16 125.73) (xy 273.05 125.73)
		)
		(stroke
			(width 0)
			(type default)
		)
	)
	(wire
		(pts
			(xy 271.78 190.5) (xy 271.78 198.12)
		)
		(stroke
			(width 0)
			(type default)
		)
	)
	(wire
		(pts
			(xy 179.07 157.48) (xy 186.69 157.48)
		)
		(stroke
			(width 0)
			(type default)
		)
	)
	(wire
		(pts
			(xy 132.08 217.17) (xy 134.62 217.17)
		)
		(stroke
			(width 0)
			(type default)
		)
	)
	(wire
		(pts
			(xy 124.46 190.5) (xy 124.46 193.04)
		)
		(stroke
			(width 0)
			(type default)
		)
	)
	(bus
		(pts
			(xy 137.16 118.11) (xy 273.05 118.11)
		)
		(stroke
			(width 0)
			(type default)
		)
	)
	(wire
		(pts
			(xy 186.69 157.48) (xy 186.69 133.35)
		)
		(stroke
			(width 0)
			(type default)
		)
	)
	(wire
		(pts
			(xy 123.19 190.5) (xy 124.46 190.5)
		)
		(stroke
			(width 0)
			(type default)
		)
	)
	(bus
		(pts
			(xy 251.46 158.75) (xy 254 158.75)
		)
		(stroke
			(width 0)
			(type default)
		)
	)
	(wire
		(pts
			(xy 116.84 219.71) (xy 116.84 224.79)
		)
		(stroke
			(width 0)
			(type default)
		)
	)
	(bus
		(pts
			(xy 137.16 120.65) (xy 254 120.65)
		)
		(stroke
			(width 0)
			(type default)
		)
	)
	(netclass_flag ""
		(length 2.54)
		(shape round)
		(at 137.16 186.69 0)
		(effects
			(font
				(size 1.27 1.27)
				(color 255 0 0 1)
			)
			(justify left bottom)
		)
		(property "Netclass" "PWR"
			(at 137.16 182.626 0)
			(effects
				(font
					(size 1.27 1.27)
				)
			)
		)
		(property "Component Class" ""
			(at -236.22 142.24 0)
			(effects
				(font
					(size 1.27 1.27)
					(italic yes)
				)
			)
		)
	)
	(netclass_flag ""
		(length 2.54)
		(shape round)
		(at 137.16 210.82 0)
		(effects
			(font
				(size 1.27 1.27)
				(color 255 0 0 1)
			)
			(justify left bottom)
		)
		(property "Netclass" "PWR"
			(at 137.16 206.756 0)
			(effects
				(font
					(size 1.27 1.27)
				)
			)
		)
		(property "Component Class" ""
			(at -236.22 166.37 0)
			(effects
				(font
					(size 1.27 1.27)
					(italic yes)
				)
			)
		)
	)
	(symbol
		(lib_id "antmicroWire2BoardConnectors:Molex_Nano-Fit_1x2_SMD_1054301202")
		(at 123.19 187.96 0)
		(mirror y)
		(unit 1)
		(exclude_from_sim no)
		(in_bom yes)
		(on_board yes)
		(dnp no)
		(fields_autoplaced yes)
		(property "Reference" "J4"
			(at 118.745 180.34 0)
			(effects
				(font
					(size 1.27 1.27)
					(thickness 0.15)
				)
			)
		)
		(property "Value" "Molex_Nano-Fit_1x2_SMD_1054301202"
			(at 96.52 195.58 0)
			(effects
				(font
					(size 1.27 1.27)
					(thickness 0.15)
				)
				(justify left bottom)
				(hide yes)
			)
		)
		(property "Footprint" "antmicro-footprints:Conn_Molex_Nano-Fit_1x2_SMD_1054301202"
			(at 96.52 198.12 0)
			(effects
				(font
					(size 1.27 1.27)
					(thickness 0.15)
				)
				(justify left bottom)
				(hide yes)
			)
		)
		(property "Datasheet" "https://www.farnell.com/cad/3578051.pdf"
			(at 96.52 200.66 0)
			(effects
				(font
					(size 1.27 1.27)
					(thickness 0.15)
				)
				(justify left bottom)
				(hide yes)
			)
		)
		(property "Description" "Pin Header, Pitch 2.5 mm, 1 Row, 2 Contacts, Nano-Fit"
			(at 123.19 187.96 0)
			(effects
				(font
					(size 1.27 1.27)
				)
				(hide yes)
			)
		)
		(property "Manufacturer" "Molex"
			(at 96.52 203.2 0)
			(effects
				(font
					(size 1.27 1.27)
					(thickness 0.15)
				)
				(justify left bottom)
				(hide yes)
			)
		)
		(property "MPN" "105430-1202"
			(at 118.745 182.88 0)
			(effects
				(font
					(size 1.27 1.27)
					(thickness 0.15)
				)
			)
		)
		(property "Author" "Antmicro"
			(at 96.52 205.74 0)
			(effects
				(font
					(size 1.27 1.27)
					(thickness 0.15)
				)
				(justify left bottom)
				(hide yes)
			)
		)
		(property "License" "Apache-2.0"
			(at 96.52 208.28 0)
			(effects
				(font
					(size 1.27 1.27)
					(thickness 0.15)
				)
				(justify left bottom)
				(hide yes)
			)
		)
		(pin "MP"
		)
		(pin "1"
		)
		(pin "2"
		)
		(instances
			(project ""
				(path ""
					(reference "J4")
					(unit 1)
				)
			)
		)
	)
	(symbol
		(lib_id "antmicroResistors0603:R_0R_22.4A_0603")
		(at 147.32 201.93 270)
		(mirror x)
		(unit 1)
		(exclude_from_sim no)
		(in_bom no)
		(on_board yes)
		(dnp yes)
		(property "Reference" "R45"
			(at 145.796 196.85 90)
			(effects
				(font
					(size 1.27 1.27)
					(thickness 0.15)
				)
				(justify right)
			)
		)
		(property "Value" "R_0R_22.4A_0603"
			(at 145.542 198.12 90)
			(effects
				(font
					(size 1.27 1.27)
					(thickness 0.15)
				)
				(justify right)
				(hide yes)
			)
		)
		(property "Footprint" "antmicro-footprints:R_0603_1608Metric"
			(at 137.16 186.69 0)
			(effects
				(font
					(size 1.27 1.27)
					(thickness 0.15)
				)
				(justify left bottom)
				(hide yes)
			)
		)
		(property "Datasheet" "https://fscdn.rohm.com/en/products/databook/datasheet/passive/resistor/chip_resistor/pmr-jpw-e.pdf"
			(at 134.62 186.69 0)
			(effects
				(font
					(size 1.27 1.27)
					(thickness 0.15)
				)
				(justify left bottom)
				(hide yes)
			)
		)
		(property "Description" "SMD Chip Resistor"
			(at 147.32 201.93 0)
			(effects
				(font
					(size 1.27 1.27)
				)
				(hide yes)
			)
		)
		(property "MPN" "PMR03EZPJ000"
			(at 132.08 186.69 0)
			(effects
				(font
					(size 1.27 1.27)
					(thickness 0.15)
				)
				(justify left bottom)
				(hide yes)
			)
		)
		(property "Manufacturer" "ROHM Semiconductor"
			(at 129.54 186.69 0)
			(effects
				(font
					(size 1.27 1.27)
					(thickness 0.15)
				)
				(justify left bottom)
				(hide yes)
			)
		)
		(property "Val" "0R"
			(at 145.796 199.39 90)
			(effects
				(font
					(size 1.27 1.27)
					(thickness 0.15)
				)
				(justify right)
			)
		)
		(property "Max. Curr." "22.4A"
			(at 145.796 201.93 90)
			(effects
				(font
					(size 1.27 1.27)
					(thickness 0.15)
				)
				(justify right)
			)
		)
		(property "Author" "Antmicro"
			(at 124.46 186.69 0)
			(effects
				(font
					(size 1.27 1.27)
					(thickness 0.15)
				)
				(justify left bottom)
				(hide yes)
			)
		)
		(property "License" "Apache-2.0"
			(at 121.92 186.69 0)
			(effects
				(font
					(size 1.27 1.27)
					(thickness 0.15)
				)
				(justify left bottom)
				(hide yes)
			)
		)
		(property "Tolerance" "template_tolerance"
			(at 137.16 181.61 0)
			(effects
				(font
					(size 1.27 1.27)
				)
				(justify left bottom)
				(hide yes)
			)
		)
		(pin "1"
		)
		(pin "2"
		)
		(instances
			(project ""
				(path ""
					(reference "R45")
					(unit 1)
				)
			)
		)
	)
	(symbol
		(lib_id "antmicroMechanicalParts:MP_Pad6mm_Drill3.2mm")
		(at 274.32 175.26 0)
		(unit 1)
		(exclude_from_sim no)
		(in_bom no)
		(on_board yes)
		(dnp no)
		(fields_autoplaced yes)
		(property "Reference" "MP2"
			(at 283.21 173.99 0)
			(effects
				(font
					(size 1.27 1.27)
					(thickness 0.15)
				)
				(justify left)
			)
		)
		(property "Value" "MP_Pad6mm_Drill3.2mm"
			(at 283.21 176.53 0)
			(effects
				(font
					(size 1.27 1.27)
					(thickness 0.15)
				)
				(justify left)
			)
		)
		(property "Footprint" "antmicro-footprints:MP_Pad6mm_Drill3.2mm"
			(at 294.64 182.88 0)
			(effects
				(font
					(size 1.27 1.27)
					(thickness 0.15)
				)
				(justify left bottom)
				(hide yes)
			)
		)
		(property "Datasheet" ""
			(at 291.16 190.83 0)
			(effects
				(font
					(size 1.27 1.27)
					(thickness 0.15)
				)
				(justify left bottom)
				(hide yes)
			)
		)
		(property "Description" "Mechanical part"
			(at 274.32 175.26 0)
			(effects
				(font
					(size 1.27 1.27)
				)
				(hide yes)
			)
		)
		(property "Author" "Antmicro"
			(at 294.64 185.42 0)
			(effects
				(font
					(size 1.27 1.27)
					(thickness 0.15)
				)
				(justify left bottom)
				(hide yes)
			)
		)
		(property "License" "Apache-2.0"
			(at 294.64 187.96 0)
			(effects
				(font
					(size 1.27 1.27)
					(thickness 0.15)
				)
				(justify left bottom)
				(hide yes)
			)
		)
		(pin "1"
		)
		(instances
			(project "oculink-to-pcie-adapter"
				(path ""
					(reference "MP2")
					(unit 1)
				)
			)
		)
	)
	(symbol
		(lib_id "antmicroMechanicalParts:MP_Pad6mm_Drill3.2mm")
		(at 274.32 167.64 0)
		(unit 1)
		(exclude_from_sim no)
		(in_bom no)
		(on_board yes)
		(dnp no)
		(fields_autoplaced yes)
		(property "Reference" "MP1"
			(at 283.21 166.37 0)
			(effects
				(font
					(size 1.27 1.27)
					(thickness 0.15)
				)
				(justify left)
			)
		)
		(property "Value" "MP_Pad6mm_Drill3.2mm"
			(at 283.21 168.91 0)
			(effects
				(font
					(size 1.27 1.27)
					(thickness 0.15)
				)
				(justify left)
			)
		)
		(property "Footprint" "antmicro-footprints:MP_Pad6mm_Drill3.2mm"
			(at 294.64 175.26 0)
			(effects
				(font
					(size 1.27 1.27)
					(thickness 0.15)
				)
				(justify left bottom)
				(hide yes)
			)
		)
		(property "Datasheet" ""
			(at 291.16 183.21 0)
			(effects
				(font
					(size 1.27 1.27)
					(thickness 0.15)
				)
				(justify left bottom)
				(hide yes)
			)
		)
		(property "Description" "Mechanical part"
			(at 274.32 167.64 0)
			(effects
				(font
					(size 1.27 1.27)
				)
				(hide yes)
			)
		)
		(property "Author" "Antmicro"
			(at 294.64 177.8 0)
			(effects
				(font
					(size 1.27 1.27)
					(thickness 0.15)
				)
				(justify left bottom)
				(hide yes)
			)
		)
		(property "License" "Apache-2.0"
			(at 294.64 180.34 0)
			(effects
				(font
					(size 1.27 1.27)
					(thickness 0.15)
				)
				(justify left bottom)
				(hide yes)
			)
		)
		(pin "1"
		)
		(instances
			(project ""
				(path ""
					(reference "MP1")
					(unit 1)
				)
			)
		)
	)
	(symbol
		(lib_id "antmicropower:GND")
		(at 116.84 224.79 0)
		(mirror y)
		(unit 1)
		(exclude_from_sim no)
		(in_bom yes)
		(on_board yes)
		(dnp no)
		(property "Reference" "#PWR083"
			(at 107.95 227.33 0)
			(effects
				(font
					(size 1.27 1.27)
					(thickness 0.15)
				)
				(justify left bottom)
				(hide yes)
			)
		)
		(property "Value" "GND"
			(at 116.84 228.6 0)
			(effects
				(font
					(size 1.27 1.27)
					(thickness 0.15)
				)
			)
		)
		(property "Footprint" ""
			(at 107.95 232.41 0)
			(effects
				(font
					(size 1.27 1.27)
					(thickness 0.15)
				)
				(justify left bottom)
				(hide yes)
			)
		)
		(property "Datasheet" ""
			(at 107.95 237.49 0)
			(effects
				(font
					(size 1.27 1.27)
					(thickness 0.15)
				)
				(justify left bottom)
				(hide yes)
			)
		)
		(property "Description" ""
			(at 116.84 224.79 0)
			(effects
				(font
					(size 1.27 1.27)
				)
				(hide yes)
			)
		)
		(property "Author" "Antmicro"
			(at 107.95 232.41 0)
			(effects
				(font
					(size 1.27 1.27)
					(thickness 0.15)
				)
				(justify left bottom)
				(hide yes)
			)
		)
		(property "License" "Apache-2.0"
			(at 107.95 234.95 0)
			(effects
				(font
					(size 1.27 1.27)
					(thickness 0.15)
				)
				(justify left bottom)
				(hide yes)
			)
		)
		(pin "1"
		)
		(instances
			(project "oculink-to-pcie-adapter"
				(path ""
					(reference "#PWR083")
					(unit 1)
				)
			)
		)
	)
	(symbol
		(lib_id "antmicroMechanicalParts:MP_Pad6mm_Drill3.2mm")
		(at 274.32 198.12 0)
		(unit 1)
		(exclude_from_sim no)
		(in_bom no)
		(on_board yes)
		(dnp no)
		(fields_autoplaced yes)
		(property "Reference" "MP5"
			(at 283.21 196.85 0)
			(effects
				(font
					(size 1.27 1.27)
					(thickness 0.15)
				)
				(justify left)
			)
		)
		(property "Value" "MP_Pad6mm_Drill3.2mm"
			(at 283.21 199.39 0)
			(effects
				(font
					(size 1.27 1.27)
					(thickness 0.15)
				)
				(justify left)
			)
		)
		(property "Footprint" "antmicro-footprints:MP_Pad6mm_Drill3.2mm"
			(at 294.64 205.74 0)
			(effects
				(font
					(size 1.27 1.27)
					(thickness 0.15)
				)
				(justify left bottom)
				(hide yes)
			)
		)
		(property "Datasheet" ""
			(at 291.16 213.69 0)
			(effects
				(font
					(size 1.27 1.27)
					(thickness 0.15)
				)
				(justify left bottom)
				(hide yes)
			)
		)
		(property "Description" "Mechanical part"
			(at 274.32 198.12 0)
			(effects
				(font
					(size 1.27 1.27)
				)
				(hide yes)
			)
		)
		(property "Author" "Antmicro"
			(at 294.64 208.28 0)
			(effects
				(font
					(size 1.27 1.27)
					(thickness 0.15)
				)
				(justify left bottom)
				(hide yes)
			)
		)
		(property "License" "Apache-2.0"
			(at 294.64 210.82 0)
			(effects
				(font
					(size 1.27 1.27)
					(thickness 0.15)
				)
				(justify left bottom)
				(hide yes)
			)
		)
		(pin "1"
		)
		(instances
			(project "oculink-to-pcie-adapter"
				(path ""
					(reference "MP5")
					(unit 1)
				)
			)
		)
	)
	(symbol
		(lib_id "antmicroWire2BoardConnectors:Molex_Mini-Fit-Jr_2x4_39-28-8080")
		(at 132.08 212.09 0)
		(mirror y)
		(unit 1)
		(exclude_from_sim no)
		(in_bom yes)
		(on_board yes)
		(dnp no)
		(fields_autoplaced yes)
		(property "Reference" "J5"
			(at 125.73 205.74 0)
			(effects
				(font
					(size 1.27 1.27)
					(thickness 0.15)
				)
			)
		)
		(property "Value" "Molex_Mini-Fit-Jr_2x4_39-28-8080"
			(at 105.41 220.98 0)
			(effects
				(font
					(size 1.27 1.27)
					(thickness 0.15)
				)
				(justify left bottom)
				(hide yes)
			)
		)
		(property "Footprint" "antmicro-footprints:MOLEX_39288080"
			(at 105.41 223.52 0)
			(effects
				(font
					(size 1.27 1.27)
					(thickness 0.15)
				)
				(justify left bottom)
				(hide yes)
			)
		)
		(property "Datasheet" "https://www.molex.com/pdm_docs/sd/039288080_sd.pdf"
			(at 105.41 226.06 0)
			(effects
				(font
					(size 1.27 1.27)
					(thickness 0.15)
				)
				(justify left bottom)
				(hide yes)
			)
		)
		(property "Description" "Pin Header, THT, Vertical, UL94V-2, Power, Wire-to-Board, 4.2 mm, 2 Rows, 8 Contacts, Mini-fit Jr, 5566 series"
			(at 132.08 212.09 0)
			(effects
				(font
					(size 1.27 1.27)
				)
				(hide yes)
			)
		)
		(property "MPN" "39-28-8080"
			(at 125.73 208.28 0)
			(effects
				(font
					(size 1.27 1.27)
					(thickness 0.15)
				)
			)
		)
		(property "Manufacturer" "Molex"
			(at 105.41 228.6 0)
			(effects
				(font
					(size 1.27 1.27)
					(thickness 0.15)
				)
				(justify left bottom)
				(hide yes)
			)
		)
		(property "Author" "Antmicro"
			(at 105.41 231.14 0)
			(effects
				(font
					(size 1.27 1.27)
					(thickness 0.15)
				)
				(justify left bottom)
				(hide yes)
			)
		)
		(property "License" "Apache-2.0"
			(at 105.41 233.68 0)
			(effects
				(font
					(size 1.27 1.27)
					(thickness 0.15)
				)
				(justify left bottom)
				(hide yes)
			)
		)
		(pin "6"
		)
		(pin "5"
		)
		(pin "8"
		)
		(pin "3"
		)
		(pin "2"
		)
		(pin "1"
		)
		(pin "4"
		)
		(pin "7"
		)
		(instances
			(project ""
				(path ""
					(reference "J5")
					(unit 1)
				)
			)
		)
	)
	(symbol
		(lib_id "antmicropower:GND")
		(at 124.46 194.31 0)
		(mirror y)
		(unit 1)
		(exclude_from_sim no)
		(in_bom yes)
		(on_board yes)
		(dnp no)
		(property "Reference" "#PWR057"
			(at 115.57 196.85 0)
			(effects
				(font
					(size 1.27 1.27)
					(thickness 0.15)
				)
				(justify left bottom)
				(hide yes)
			)
		)
		(property "Value" "GND"
			(at 124.46 198.12 0)
			(effects
				(font
					(size 1.27 1.27)
					(thickness 0.15)
				)
			)
		)
		(property "Footprint" ""
			(at 115.57 201.93 0)
			(effects
				(font
					(size 1.27 1.27)
					(thickness 0.15)
				)
				(justify left bottom)
				(hide yes)
			)
		)
		(property "Datasheet" ""
			(at 115.57 207.01 0)
			(effects
				(font
					(size 1.27 1.27)
					(thickness 0.15)
				)
				(justify left bottom)
				(hide yes)
			)
		)
		(property "Description" ""
			(at 124.46 194.31 0)
			(effects
				(font
					(size 1.27 1.27)
				)
				(hide yes)
			)
		)
		(property "Author" "Antmicro"
			(at 115.57 201.93 0)
			(effects
				(font
					(size 1.27 1.27)
					(thickness 0.15)
				)
				(justify left bottom)
				(hide yes)
			)
		)
		(property "License" "Apache-2.0"
			(at 115.57 204.47 0)
			(effects
				(font
					(size 1.27 1.27)
					(thickness 0.15)
				)
				(justify left bottom)
				(hide yes)
			)
		)
		(pin "1"
		)
		(instances
			(project "oculink-to-pcie-adapter"
				(path ""
					(reference "#PWR057")
					(unit 1)
				)
			)
		)
	)
	(symbol
		(lib_id "antmicropower:GND")
		(at 271.78 199.39 0)
		(mirror y)
		(unit 1)
		(exclude_from_sim no)
		(in_bom yes)
		(on_board yes)
		(dnp no)
		(property "Reference" "#PWR01"
			(at 262.89 201.93 0)
			(effects
				(font
					(size 1.27 1.27)
					(thickness 0.15)
				)
				(justify left bottom)
				(hide yes)
			)
		)
		(property "Value" "GND"
			(at 271.78 203.2 0)
			(effects
				(font
					(size 1.27 1.27)
					(thickness 0.15)
				)
			)
		)
		(property "Footprint" ""
			(at 262.89 207.01 0)
			(effects
				(font
					(size 1.27 1.27)
					(thickness 0.15)
				)
				(justify left bottom)
				(hide yes)
			)
		)
		(property "Datasheet" ""
			(at 262.89 212.09 0)
			(effects
				(font
					(size 1.27 1.27)
					(thickness 0.15)
				)
				(justify left bottom)
				(hide yes)
			)
		)
		(property "Description" ""
			(at 271.78 199.39 0)
			(effects
				(font
					(size 1.27 1.27)
				)
				(hide yes)
			)
		)
		(property "Author" "Antmicro"
			(at 262.89 207.01 0)
			(effects
				(font
					(size 1.27 1.27)
					(thickness 0.15)
				)
				(justify left bottom)
				(hide yes)
			)
		)
		(property "License" "Apache-2.0"
			(at 262.89 209.55 0)
			(effects
				(font
					(size 1.27 1.27)
					(thickness 0.15)
				)
				(justify left bottom)
				(hide yes)
			)
		)
		(pin "1"
		)
		(instances
			(project "oculink-to-pcie-adapter"
				(path ""
					(reference "#PWR01")
					(unit 1)
				)
			)
		)
	)
	(symbol
		(lib_id "antmicroMechanicalParts:MP_Pad6mm_Drill3.2mm")
		(at 274.32 182.88 0)
		(unit 1)
		(exclude_from_sim no)
		(in_bom no)
		(on_board yes)
		(dnp no)
		(fields_autoplaced yes)
		(property "Reference" "MP3"
			(at 283.21 181.61 0)
			(effects
				(font
					(size 1.27 1.27)
					(thickness 0.15)
				)
				(justify left)
			)
		)
		(property "Value" "MP_Pad6mm_Drill3.2mm"
			(at 283.21 184.15 0)
			(effects
				(font
					(size 1.27 1.27)
					(thickness 0.15)
				)
				(justify left)
			)
		)
		(property "Footprint" "antmicro-footprints:MP_Pad6mm_Drill3.2mm"
			(at 294.64 190.5 0)
			(effects
				(font
					(size 1.27 1.27)
					(thickness 0.15)
				)
				(justify left bottom)
				(hide yes)
			)
		)
		(property "Datasheet" ""
			(at 291.16 198.45 0)
			(effects
				(font
					(size 1.27 1.27)
					(thickness 0.15)
				)
				(justify left bottom)
				(hide yes)
			)
		)
		(property "Description" "Mechanical part"
			(at 274.32 182.88 0)
			(effects
				(font
					(size 1.27 1.27)
				)
				(hide yes)
			)
		)
		(property "Author" "Antmicro"
			(at 294.64 193.04 0)
			(effects
				(font
					(size 1.27 1.27)
					(thickness 0.15)
				)
				(justify left bottom)
				(hide yes)
			)
		)
		(property "License" "Apache-2.0"
			(at 294.64 195.58 0)
			(effects
				(font
					(size 1.27 1.27)
					(thickness 0.15)
				)
				(justify left bottom)
				(hide yes)
			)
		)
		(pin "1"
		)
		(instances
			(project "oculink-to-pcie-adapter"
				(path ""
					(reference "MP3")
					(unit 1)
				)
			)
		)
	)
	(symbol
		(lib_id "antmicroMechanicalParts:MP_Pad6mm_Drill3.2mm")
		(at 274.32 190.5 0)
		(unit 1)
		(exclude_from_sim no)
		(in_bom no)
		(on_board yes)
		(dnp no)
		(fields_autoplaced yes)
		(property "Reference" "MP4"
			(at 283.21 189.23 0)
			(effects
				(font
					(size 1.27 1.27)
					(thickness 0.15)
				)
				(justify left)
			)
		)
		(property "Value" "MP_Pad6mm_Drill3.2mm"
			(at 283.21 191.77 0)
			(effects
				(font
					(size 1.27 1.27)
					(thickness 0.15)
				)
				(justify left)
			)
		)
		(property "Footprint" "antmicro-footprints:MP_Pad6mm_Drill3.2mm"
			(at 294.64 198.12 0)
			(effects
				(font
					(size 1.27 1.27)
					(thickness 0.15)
				)
				(justify left bottom)
				(hide yes)
			)
		)
		(property "Datasheet" ""
			(at 291.16 206.07 0)
			(effects
				(font
					(size 1.27 1.27)
					(thickness 0.15)
				)
				(justify left bottom)
				(hide yes)
			)
		)
		(property "Description" "Mechanical part"
			(at 274.32 190.5 0)
			(effects
				(font
					(size 1.27 1.27)
				)
				(hide yes)
			)
		)
		(property "Author" "Antmicro"
			(at 294.64 200.66 0)
			(effects
				(font
					(size 1.27 1.27)
					(thickness 0.15)
				)
				(justify left bottom)
				(hide yes)
			)
		)
		(property "License" "Apache-2.0"
			(at 294.64 203.2 0)
			(effects
				(font
					(size 1.27 1.27)
					(thickness 0.15)
				)
				(justify left bottom)
				(hide yes)
			)
		)
		(pin "1"
		)
		(instances
			(project "oculink-to-pcie-adapter"
				(path ""
					(reference "MP4")
					(unit 1)
				)
			)
		)
	)
	(sheet
		(at 273.05 115.57)
		(size 30.48 30.48)
		(exclude_from_sim no)
		(in_bom yes)
		(on_board yes)
		(dnp no)
		(fields_autoplaced yes)
		(stroke
			(width 0.1524)
			(type solid)
		)
		(fill
			(color 0 0 0 0.0000)
		)
		(property "Sheetname" "PCIe-connector"
			(at 273.05 114.8584 0)
			(effects
				(font
					(size 1.27 1.27)
				)
				(justify left bottom)
			)
		)
		(property "Sheetfile" "pcie-connector.kicad_sch"
			(at 273.05 146.6346 0)
			(effects
				(font
					(size 1.27 1.27)
				)
				(justify left top)
			)
		)
		(pin "PCIe_{x4}{PCIe}" bidirectional
			(at 273.05 118.11 180)
			(effects
				(font
					(size 1.27 1.27)
				)
				(justify left)
			)
		)
		(pin "I2C0{I2C}" bidirectional
			(at 273.05 125.73 180)
			(effects
				(font
					(size 1.27 1.27)
				)
				(justify left)
			)
		)
		(pin "PCIe_{REF0}{PCIe_{REF}}" input
			(at 273.05 120.65 180)
			(effects
				(font
					(size 1.27 1.27)
				)
				(justify left)
			)
		)
		(pin "~{WAKE}" output
			(at 273.05 128.27 180)
			(effects
				(font
					(size 1.27 1.27)
				)
				(justify left)
			)
		)
		(pin "~{PERST}" input
			(at 273.05 130.81 180)
			(effects
				(font
					(size 1.27 1.27)
				)
				(justify left)
			)
		)
		(instances
			(project "oculink-to-pcie-adapter"
				(path ""
					(page "3")
				)
			)
		)
	)
	(sheet
		(at 153.67 154.94)
		(size 25.4 59.69)
		(exclude_from_sim no)
		(in_bom yes)
		(on_board yes)
		(dnp no)
		(fields_autoplaced yes)
		(stroke
			(width 0.1524)
			(type solid)
		)
		(fill
			(color 0 0 0 0.0000)
		)
		(property "Sheetname" "Power"
			(at 153.67 154.2284 0)
			(effects
				(font
					(size 1.27 1.27)
				)
				(justify left bottom)
			)
		)
		(property "Sheetfile" "power.kicad_sch"
			(at 153.67 215.2146 0)
			(effects
				(font
					(size 1.27 1.27)
				)
				(justify left top)
			)
		)
		(pin "~{CPRSNT}" output
			(at 179.07 157.48 0)
			(effects
				(font
					(size 1.27 1.27)
				)
				(justify right)
			)
		)
		(pin "VCC_PD" input
			(at 153.67 161.29 180)
			(effects
				(font
					(size 1.27 1.27)
				)
				(justify left)
			)
		)
		(pin "~{PERST_CONN}" input
			(at 179.07 160.02 0)
			(effects
				(font
					(size 1.27 1.27)
				)
				(justify right)
			)
		)
		(pin "~{PERST}" output
			(at 179.07 162.56 0)
			(effects
				(font
					(size 1.27 1.27)
				)
				(justify right)
			)
		)
		(pin "VCC_DC_CONN_1" input
			(at 153.67 187.96 180)
			(effects
				(font
					(size 1.27 1.27)
				)
				(justify left)
			)
		)
		(pin "VCC_DC_CONN_2" input
			(at 153.67 212.09 180)
			(effects
				(font
					(size 1.27 1.27)
				)
				(justify left)
			)
		)
		(instances
			(project "oculink-to-pcie-adapter"
				(path ""
					(page "4")
				)
			)
		)
	)
	(sheet
		(at 111.76 115.57)
		(size 25.4 30.48)
		(exclude_from_sim no)
		(in_bom yes)
		(on_board yes)
		(dnp no)
		(fields_autoplaced yes)
		(stroke
			(width 0.1524)
			(type solid)
		)
		(fill
			(color 0 0 0 0.0000)
		)
		(property "Sheetname" "OCuLink"
			(at 111.76 114.8584 0)
			(effects
				(font
					(size 1.27 1.27)
				)
				(justify left bottom)
			)
		)
		(property "Sheetfile" "oculink.kicad_sch"
			(at 111.76 146.6346 0)
			(effects
				(font
					(size 1.27 1.27)
				)
				(justify left top)
			)
		)
		(pin "PCIe_{x4}{PCIe}" bidirectional
			(at 137.16 118.11 0)
			(effects
				(font
					(size 1.27 1.27)
				)
				(justify right)
			)
		)
		(pin "I2C0{I2C}" bidirectional
			(at 137.16 125.73 0)
			(effects
				(font
					(size 1.27 1.27)
				)
				(justify right)
			)
		)
		(pin "PCIe_{REF0}{PCIe_{REF}}" output
			(at 137.16 120.65 0)
			(effects
				(font
					(size 1.27 1.27)
				)
				(justify right)
			)
		)
		(pin "~{WAKE}" input
			(at 137.16 128.27 0)
			(effects
				(font
					(size 1.27 1.27)
				)
				(justify right)
			)
		)
		(pin "~{CPRSNT}" input
			(at 137.16 133.35 0)
			(effects
				(font
					(size 1.27 1.27)
				)
				(justify right)
			)
		)
		(pin "~{PERST}" output
			(at 137.16 130.81 0)
			(effects
				(font
					(size 1.27 1.27)
				)
				(justify right)
			)
		)
		(instances
			(project "oculink-to-pcie-adapter"
				(path ""
					(page "2")
				)
			)
		)
	)
	(sheet
		(at 111.76 154.94)
		(size 25.4 12.7)
		(exclude_from_sim no)
		(in_bom yes)
		(on_board yes)
		(dnp no)
		(fields_autoplaced yes)
		(stroke
			(width 0.1524)
			(type solid)
		)
		(fill
			(color 0 0 0 0.0000)
		)
		(property "Sheetname" "USB-PD"
			(at 111.76 154.2284 0)
			(effects
				(font
					(size 1.27 1.27)
				)
				(justify left bottom)
			)
		)
		(property "Sheetfile" "usb-pd.kicad_sch"
			(at 111.76 168.2246 0)
			(effects
				(font
					(size 1.27 1.27)
				)
				(justify left top)
			)
		)
		(pin "12V_OUT" output
			(at 137.16 161.29 0)
			(effects
				(font
					(size 1.27 1.27)
				)
				(justify right)
			)
		)
		(instances
			(project "oculink-to-pcie-adapter"
				(path ""
					(page "5")
				)
			)
		)
	)
	(sheet
		(at 215.9 154.94)
		(size 35.56 7.62)
		(exclude_from_sim no)
		(in_bom no)
		(on_board yes)
		(dnp yes)
		(fields_autoplaced yes)
		(stroke
			(width 0.1524)
			(type solid)
		)
		(fill
			(color 0 0 0 0.0000)
		)
		(property "Sheetname" "PCIe-clock-generator"
			(at 215.9 154.2284 0)
			(effects
				(font
					(size 1.27 1.27)
				)
				(justify left bottom)
			)
		)
		(property "Sheetfile" "pcie-clock-generator.kicad_sch"
			(at 215.9 163.1446 0)
			(effects
				(font
					(size 1.27 1.27)
				)
				(justify left top)
			)
		)
		(pin "PCIe_{REF1}{PCIe_{REF}}" output
			(at 251.46 158.75 0)
			(effects
				(font
					(size 1.27 1.27)
				)
				(justify right)
			)
		)
		(instances
			(project "oculink-to-pcie-adapter"
				(path ""
					(page "8")
				)
			)
		)
	)
	(sheet_instances
		(path "/"
			(page "1")
		)
	)
)
